# BASEBOARD_FAB2 (Tioga Pass) — schematic netlist excerpt (pin names and nets, part order shuffled) for the footprints in the layout excerpt that follows; sources: Cadence DE-HDL packaged netlist, KiCad conversion of Wiwynn_Tioga_Pass_MB.brd

RF12  RES  1.0K 0.1% CHIP  pkg 0402  page 206 : A = VR_PVSA_CPU1_BIREF1 ; B = ISENSE_PVSA_CPU1_IMON
RT24  1R3F-GP  1%  pkg RCL_GP  page 204 : \1\ = VR_PVCCIN_CPU0_PHASE5_RC ; \2\ = GND
C842  CAP  0.22UF 16V 10% X7R  pkg 0402  page 244 : A = P3E_CPU0_PE1_PCH_TXN<8> ; B = P3E_CPU0_PE1_PCH_CON_TXN<8>

(kicad_pcb
	(version 20260206)
	(generator "pcbnew")
	(generator_version "10.0")
	(general
		(thickness 1.6)
		(legacy_teardrops no)
	)
	(paper "A4")
	(title_block
		(title "Wiwynn_Tioga_Pass_MB.brd")
		(comment 1 "Tioga Pass / footprints 2191-2193 of 4770")
	)
	(layers
		(0 "F.Cu" signal "TOP")
		(4 "In1.Cu" signal "L2GND")
		(6 "In2.Cu" signal "L3")
		(8 "In3.Cu" signal "L4GND")
		(10 "In4.Cu" signal "L5")
		(12 "In5.Cu" signal "L6GND")
		(14 "In6.Cu" signal "L7VCC")
		(16 "In7.Cu" signal "L8VCC")
		(18 "In8.Cu" signal "L9GND")
		(20 "In9.Cu" signal "L10")
		(22 "In10.Cu" signal "L11GND")
		(24 "In11.Cu" signal "L12")
		(26 "In12.Cu" signal "L13GND")
		(2 "B.Cu" signal "BOTTOM")
		(9 "F.Adhes" user "F.Adhesive")
		(11 "B.Adhes" user "B.Adhesive")
		(13 "F.Paste" user "Package Geometry/Pastemask Top")
		(15 "B.Paste" user "Package Geometry/Pastemask Bottom")
		(5 "F.SilkS" user "Ref Des/Silkscreen Top")
		(7 "B.SilkS" user "Ref Des/Silkscreen Bottom")
		(1 "F.Mask" user "Board Geometry/Soldermask Top")
		(3 "B.Mask" user "Board Geometry/Soldermask Bottom")
		(17 "Dwgs.User" user "User.Drawings")
		(19 "Cmts.User" user "User.Comments")
		(21 "Eco1.User" user "User.Eco1")
		(23 "Eco2.User" user "User.Eco2")
		(25 "Edge.Cuts" user "Board Geometry/Outline")
		(27 "Margin" user)
		(31 "F.CrtYd" user "Package Geometry/Place Bound Top")
		(29 "B.CrtYd" user "Package Geometry/Place Bound Bottom")
		(35 "F.Fab" user "Ref Des/Assembly Top")
		(33 "B.Fab" user "Ref Des/Assembly Bottom")
	)
	(footprint ""
		(layer "F.Cu")
		(at 332.90002 -118.5164 -90)
		(property "Reference" "C842"
			(at -0.8382 -0.67818 270)
			(unlocked yes)
			(layer "F.SilkS")
			(effects
				(font
					(size 0.4064 0.254)
					(thickness 0.1524)
				)
				(justify left)
			)
		)
		(property "Value" ""
			(at 0 0 270)
			(layer "F.Fab")
			(effects
				(font
					(size 1.27 1.27)
				)
			)
		)
		(duplicate_pad_numbers_are_jumpers no)
		(fp_poly
			(pts
				(xy 0.3048 -0.1016) (xy 0.3048 0.9906) (xy -0.3048 0.9906) (xy -0.3048 -0.1016)
			)
			(stroke
				(width 0)
				(type default)
			)
			(fill no)
			(layer "F.CrtYd")
		)
		(fp_line
			(start -0.3048 0.9906)
			(end 0.3048 0.9906)
			(stroke
				(width 0.1)
				(type default)
			)
			(layer "F.Fab")
		)
		(fp_line
			(start 0.3048 0.9906)
			(end 0.3048 -0.1016)
			(stroke
				(width 0.1)
				(type default)
			)
			(layer "F.Fab")
		)
		(fp_line
			(start -0.3048 -0.1016)
			(end -0.3048 0.9906)
			(stroke
				(width 0.1)
				(type default)
			)
			(layer "F.Fab")
		)
		(fp_line
			(start 0.3048 -0.1016)
			(end -0.3048 -0.1016)
			(stroke
				(width 0.1)
				(type default)
			)
			(layer "F.Fab")
		)
		(pad "1" smd rect
			(at 0 0 270)
			(size 0.508 0.508)
			(layers "F.Cu" "F.Mask" "F.Paste")
			(net "P3E_CPU0_PE1_PCH_TXN<8>")
		)
		(pad "2" smd rect
			(at 0 0.889 270)
			(size 0.508 0.508)
			(layers "F.Cu" "F.Mask" "F.Paste")
			(net "P3E_CPU0_PE1_PCH_CON_TXN<8>")
		)
		(zone
			(layer "F.Cu")
			(hatch none 0.5)
			(connect_pads
				(clearance 0)
			)
			(min_thickness 0.25)
			(keepout
				(tracks not_allowed)
				(vias allowed)
				(pads allowed)
				(copperpour not_allowed)
				(footprints allowed)
			)
			(placement
				(enabled no)
				(sheetname "")
			)
			(fill
				(thermal_gap 0.5)
				(thermal_bridge_width 0.5)
				(island_removal_mode 0)
			)
			(polygon
				(pts
					(xy 332.26502 -118.7704) (xy 332.26502 -118.2624) (xy 332.64602 -118.2624) (xy 332.64602 -118.7704)
				)
			)
		)
		(zone
			(layer "F.Cu")
			(hatch none 0.5)
			(connect_pads
				(clearance 0)
			)
			(min_thickness 0.25)
			(keepout
				(tracks allowed)
				(vias not_allowed)
				(pads allowed)
				(copperpour not_allowed)
				(footprints allowed)
			)
			(placement
				(enabled no)
				(sheetname "")
			)
			(fill
				(thermal_gap 0.5)
				(thermal_bridge_width 0.5)
				(island_removal_mode 0)
			)
			(polygon
				(pts
					(xy 332.64602 -118.7704) (xy 332.64602 -118.2624) (xy 332.26502 -118.2624) (xy 332.26502 -118.7704)
				)
			)
		)
	)
	(footprint ""
		(layer "F.Cu")
		(at 23.697184 -97.562416 180)
		(property "Reference" "RF12"
			(at -0.8382 -0.67818 180)
			(unlocked yes)
			(layer "F.SilkS")
			(effects
				(font
					(size 0.4064 0.254)
					(thickness 0.1524)
				)
				(justify left)
			)
		)
		(property "Value" ""
			(at 0 0 180)
			(layer "F.Fab")
			(effects
				(font
					(size 1.27 1.27)
				)
			)
		)
		(duplicate_pad_numbers_are_jumpers no)
		(fp_poly
			(pts
				(xy -0.2794 -0.1016) (xy 0.2794 -0.1016) (xy 0.2794 0.9906) (xy -0.2794 0.9906)
			)
			(stroke
				(width 0)
				(type default)
			)
			(fill no)
			(layer "F.CrtYd")
		)
		(fp_line
			(start 0.2794 0.9906)
			(end 0.2794 -0.1016)
			(stroke
				(width 0.1)
				(type default)
			)
			(layer "F.Fab")
		)
		(fp_line
			(start 0.2794 -0.1016)
			(end -0.2794 -0.1016)
			(stroke
				(width 0.1)
				(type default)
			)
			(layer "F.Fab")
		)
		(fp_line
			(start -0.2794 0.9906)
			(end 0.2794 0.9906)
			(stroke
				(width 0.1)
				(type default)
			)
			(layer "F.Fab")
		)
		(fp_line
			(start -0.2794 -0.1016)
			(end -0.2794 0.9906)
			(stroke
				(width 0.1)
				(type default)
			)
			(layer "F.Fab")
		)
		(pad "1" smd rect
			(at 0 0 180)
			(size 0.508 0.508)
			(layers "F.Cu" "F.Mask" "F.Paste")
			(net "VR_PVSA_CPU1_BIREF1")
		)
		(pad "2" smd rect
			(at 0 0.889 180)
			(size 0.508 0.508)
			(layers "F.Cu" "F.Mask" "F.Paste")
			(net "ISENSE_PVSA_CPU1_IMON")
		)
		(zone
			(layer "F.Cu")
			(hatch none 0.5)
			(connect_pads
				(clearance 0)
			)
			(min_thickness 0.25)
			(keepout
				(tracks not_allowed)
				(vias allowed)
				(pads allowed)
				(copperpour not_allowed)
				(footprints allowed)
			)
			(placement
				(enabled no)
				(sheetname "")
			)
			(fill
				(thermal_gap 0.5)
				(thermal_bridge_width 0.5)
				(island_removal_mode 0)
			)
			(polygon
				(pts
					(xy 23.951184 -98.197416) (xy 23.443184 -98.197416) (xy 23.443184 -97.816416) (xy 23.951184 -97.816416)
				)
			)
		)
		(zone
			(layer "F.Cu")
			(hatch none 0.5)
			(connect_pads
				(clearance 0)
			)
			(min_thickness 0.25)
			(keepout
				(tracks allowed)
				(vias not_allowed)
				(pads allowed)
				(copperpour not_allowed)
				(footprints allowed)
			)
			(placement
				(enabled no)
				(sheetname "")
			)
			(fill
				(thermal_gap 0.5)
				(thermal_bridge_width 0.5)
				(island_removal_mode 0)
			)
			(polygon
				(pts
					(xy 23.951184 -97.816416) (xy 23.443184 -97.816416) (xy 23.443184 -98.197416) (xy 23.951184 -98.197416)
				)
			)
		)
	)
	(footprint ""
		(layer "F.Cu")
		(at 201.422 -85.4456 -90)
		(property "Reference" "RT24"
			(at 0 0 270)
			(layer "F.SilkS")
			(hide yes)
			(effects
				(font
					(size 1.27 1.27)
				)
			)
		)
		(property "Value" "*"
			(at -0.0254 -2.6289 270)
			(unlocked yes)
			(layer "F.Fab")
			(hide yes)
			(effects
				(font
					(size 1.27 1.016)
					(thickness 0.1524)
				)
			)
		)
		(property "Device Type" "1R3F-GP_RCL_GP-1R3F-GP,64.1R00A"
			(at -0.0254 -4.1529 270)
			(unlocked yes)
			(layer "F.Fab")
			(hide yes)
			(effects
				(font
					(size 1.27 1.016)
					(thickness 0.1524)
				)
			)
		)
		(duplicate_pad_numbers_are_jumpers no)
		(fp_line
			(start -0.4826 0)
			(end -0.2032 0)
			(stroke
				(width 0.2032)
				(type default)
			)
			(layer "F.SilkS")
		)
		(fp_line
			(start 0.2032 0)
			(end 0.4826 0)
			(stroke
				(width 0.2032)
				(type default)
			)
			(layer "F.SilkS")
		)
		(fp_rect
			(start -0.5842 1.3335)
			(end 0.5842 -1.3335)
			(stroke
				(width 0)
				(type default)
			)
			(fill no)
			(layer "F.CrtYd")
		)
		(fp_rect
			(start -0.5842 1.3335)
			(end 0.5842 -1.3335)
			(stroke
				(width 0)
				(type default)
			)
			(fill no)
			(layer "F.Fab")
		)
		(pad "1" smd custom
			(at 0 -0.762 270)
			(size 0.2159 0.2159)
			(layers "F.Cu" "F.Mask" "F.Paste")
			(net "VR_PVCCIN_CPU0_PHASE5_RC")
			(options
				(clearance outline)
				(anchor circle)
			)
			(primitives
				(gr_poly
					(pts
						(arc
							(start -0.3302 -0.4318)
							(mid -0.402042 -0.402042)
							(end -0.4318 -0.3302)
						)
						(arc
							(start -0.4318 0.3302)
							(mid -0.402042 0.402042)
							(end -0.3302 0.4318)
						)
						(arc
							(start 0.3302 0.4318)
							(mid 0.402042 0.402042)
							(end 0.4318 0.3302)
						)
						(arc
							(start 0.4318 -0.3302)
							(mid 0.402042 -0.402042)
							(end 0.3302 -0.4318)
						)
					)
					(width 0)
					(fill yes)
				)
			)
		)
		(pad "2" smd custom
			(at 0 0.762 270)
			(size 0.2159 0.2159)
			(layers "F.Cu" "F.Mask" "F.Paste")
			(net "GND")
			(options
				(clearance outline)
				(anchor circle)
			)
			(primitives
				(gr_poly
					(pts
						(arc
							(start -0.3302 -0.4318)
							(mid -0.402042 -0.402042)
							(end -0.4318 -0.3302)
						)
						(arc
							(start -0.4318 0.3302)
							(mid -0.402042 0.402042)
							(end -0.3302 0.4318)
						)
						(arc
							(start 0.3302 0.4318)
							(mid 0.402042 0.402042)
							(end 0.4318 0.3302)
						)
						(arc
							(start 0.4318 -0.3302)
							(mid 0.402042 -0.402042)
							(end 0.3302 -0.4318)
						)
					)
					(width 0)
					(fill yes)
				)
			)
		)
	)
)
